(kicad_pcb
	(version 20241229)
	(generator "pcbnew")
	(generator_version "9.0")
	(general
		(thickness 1.62)
		(legacy_teardrops no)
	)
	(paper "A4")
	(title_block
		(title "OCuLink to 10GbE adapter")
		(date "2026-02-23")
		(rev "1.1.0")
		(company "Antmicro Ltd")
		(comment 1 "www.antmicro.com")
		(comment 9 "footprints 58-62 of 510")
	)
	(layers
		(0 "F.Cu" signal)
		(4 "In1.Cu" signal)
		(6 "In2.Cu" signal)
		(8 "In3.Cu" signal)
		(10 "In4.Cu" signal)
		(12 "In5.Cu" signal)
		(14 "In6.Cu" signal)
		(2 "B.Cu" signal)
		(9 "F.Adhes" user "F.Adhesive")
		(11 "B.Adhes" user "B.Adhesive")
		(13 "F.Paste" user)
		(15 "B.Paste" user)
		(5 "F.SilkS" user "F.Silkscreen")
		(7 "B.SilkS" user "B.Silkscreen")
		(1 "F.Mask" user)
		(3 "B.Mask" user)
		(17 "Dwgs.User" user "User.Drawings")
		(19 "Cmts.User" user "User.Comments")
		(21 "Eco1.User" user "User.Eco1")
		(23 "Eco2.User" user "User.Eco2")
		(25 "Edge.Cuts" user)
		(27 "Margin" user)
		(31 "F.CrtYd" user "F.Courtyard")
		(29 "B.CrtYd" user "B.Courtyard")
		(35 "F.Fab" user)
		(33 "B.Fab" user)
	)
	(footprint "antmicro-footprints:C_0603_1608Metric_EIA"
		(layer "F.Cu")
		(at 77.2 87.7 180)
		(descr "Capacitor SMD 0603, IPC-7351 Density Level A")
		(tags "Capacitor 0603")
		(property "Reference" "C150"
			(at -1.4 8.33 0)
			(layer "F.SilkS")
			(effects
				(font
					(size 0.7 0.7)
					(thickness 0.15)
				)
				(justify right top)
			)
		)
		(property "Value" "C_22u_16V_0603"
			(at -1.42757 1.770288 0)
			(layer "F.Fab")
			(hide yes)
			(effects
				(font
					(size 0.7 0.7)
					(thickness 0.15)
				)
				(justify right top)
			)
		)
		(property "Datasheet" "https://product.samsungsem.com/mlcc/CL10A226MO7JZN.do"
			(at 0 0 0)
			(layer "F.Fab")
			(hide yes)
			(effects
				(font
					(size 1.27 1.27)
					(thickness 0.15)
				)
			)
		)
		(property "Description" "SMD Multilayer Ceramic Capacitor"
			(at 0 0 0)
			(layer "F.Fab")
			(hide yes)
			(effects
				(font
					(size 1.27 1.27)
					(thickness 0.15)
				)
			)
		)
		(property "MPN" "CL10A226MO7JZNC"
			(at 0 0 180)
			(unlocked yes)
			(layer "F.Fab")
			(hide yes)
			(effects
				(font
					(size 1 1)
					(thickness 0.15)
				)
			)
		)
		(property "Manufacturer" "Samsung Electro-Mechanics"
			(at 0 0 180)
			(unlocked yes)
			(layer "F.Fab")
			(hide yes)
			(effects
				(font
					(size 1 1)
					(thickness 0.15)
				)
			)
		)
		(property "License" "Apache-2.0"
			(at 0 0 180)
			(unlocked yes)
			(layer "F.Fab")
			(hide yes)
			(effects
				(font
					(size 1 1)
					(thickness 0.15)
				)
			)
		)
		(property "Author" "Antmicro"
			(at 0 0 180)
			(unlocked yes)
			(layer "F.Fab")
			(hide yes)
			(effects
				(font
					(size 1 1)
					(thickness 0.15)
				)
			)
		)
		(property "Val" "22u"
			(at 0 0 180)
			(unlocked yes)
			(layer "F.Fab")
			(hide yes)
			(effects
				(font
					(size 1 1)
					(thickness 0.15)
				)
			)
		)
		(property "Voltage" "16V"
			(at 0 0 180)
			(unlocked yes)
			(layer "F.Fab")
			(hide yes)
			(effects
				(font
					(size 1 1)
					(thickness 0.15)
				)
			)
		)
		(property "Dielectric" ""
			(at 0 0 180)
			(unlocked yes)
			(layer "F.Fab")
			(hide yes)
			(effects
				(font
					(size 1 1)
					(thickness 0.15)
				)
			)
		)
		(sheetname "/X710-AT2 power/")
		(sheetfile "x710-at2-power.kicad_sch")
		(attr smd)
		(fp_line
			(start -0.15 0.55)
			(end 0.15 0.55)
			(stroke
				(width 0.15)
				(type solid)
			)
			(layer "F.SilkS")
		)
		(fp_line
			(start -0.15 -0.55)
			(end 0.15 -0.55)
			(stroke
				(width 0.15)
				(type solid)
			)
			(layer "F.SilkS")
		)
		(fp_rect
			(start -1.25 -0.65)
			(end 1.25 0.65)
			(stroke
				(width 0.05)
				(type solid)
			)
			(fill no)
			(layer "F.CrtYd")
		)
		(fp_rect
			(start -0.8 -0.45)
			(end 0.8 0.45)
			(stroke
				(width 0.15)
				(type solid)
			)
			(fill no)
			(layer "F.Fab")
		)
		(pad "1" smd roundrect
			(at -0.7 0 180)
			(size 0.8 1.1)
			(layers "F.Cu" "F.Mask" "F.Paste")
			(roundrect_rratio 0.2)
			(net 28 "GND")
			(pintype "passive")
		)
		(pad "2" smd roundrect
			(at 0.7 0 180)
			(size 0.8 1.1)
			(layers "F.Cu" "F.Mask" "F.Paste")
			(roundrect_rratio 0.2)
			(net 7 "+3V3")
			(pintype "passive")
		)
	)
	(footprint "antmicro-footprints:C_0603_1608Metric"
		(layer "F.Cu")
		(at 100.45 100.65)
		(descr "Capacitor SMD 0603")
		(tags "capacitor 0603")
		(property "Reference" "C158"
			(at 4.25 0.5 0)
			(layer "F.SilkS")
			(effects
				(font
					(size 0.7 0.7)
					(thickness 0.15)
				)
				(justify left bottom)
			)
		)
		(property "Value" "C_10u_10V_X7R_0603"
			(at -1.42757 1.770288 0)
			(layer "F.Fab")
			(hide yes)
			(effects
				(font
					(size 0.7 0.7)
					(thickness 0.15)
				)
				(justify left bottom)
			)
		)
		(property "Datasheet" "https://www.murata.com/products/productdetail?partno=GRM188Z71A106KA73%23"
			(at 0 0 0)
			(layer "F.Fab")
			(hide yes)
			(effects
				(font
					(size 1.27 1.27)
					(thickness 0.15)
				)
			)
		)
		(property "Description" "SMD Multilayer Ceramic Capacitor,  10µF, 10V, 0603, ±10%, X7R"
			(at 0 0 0)
			(layer "F.Fab")
			(hide yes)
			(effects
				(font
					(size 1.27 1.27)
					(thickness 0.15)
				)
			)
		)
		(property "MPN" "GRM188Z71A106KA73D"
			(at 0 0 0)
			(unlocked yes)
			(layer "F.Fab")
			(hide yes)
			(effects
				(font
					(size 1 1)
					(thickness 0.15)
				)
			)
		)
		(property "Val" "10u"
			(at 0 0 0)
			(unlocked yes)
			(layer "F.Fab")
			(hide yes)
			(effects
				(font
					(size 1 1)
					(thickness 0.15)
				)
			)
		)
		(property "Voltage" "10V"
			(at 0 0 0)
			(unlocked yes)
			(layer "F.Fab")
			(hide yes)
			(effects
				(font
					(size 1 1)
					(thickness 0.15)
				)
			)
		)
		(property "Dielectric" "X7R"
			(at 0 0 0)
			(unlocked yes)
			(layer "F.Fab")
			(hide yes)
			(effects
				(font
					(size 1 1)
					(thickness 0.15)
				)
			)
		)
		(property "Manufacturer" "Murata"
			(at 0 0 0)
			(unlocked yes)
			(layer "F.Fab")
			(hide yes)
			(effects
				(font
					(size 1 1)
					(thickness 0.15)
				)
			)
		)
		(property "License" "Apache-2.0"
			(at 0 0 0)
			(unlocked yes)
			(layer "F.Fab")
			(hide yes)
			(effects
				(font
					(size 1 1)
					(thickness 0.15)
				)
			)
		)
		(property "Author" "Antmicro"
			(at 0 0 0)
			(unlocked yes)
			(layer "F.Fab")
			(hide yes)
			(effects
				(font
					(size 1 1)
					(thickness 0.15)
				)
			)
		)
		(sheetname "/X710-AT2 power/")
		(sheetfile "x710-at2-power.kicad_sch")
		(attr smd)
		(fp_line
			(start -0.15 -0.4)
			(end 0.15 -0.4)
			(stroke
				(width 0.15)
				(type solid)
			)
			(layer "F.SilkS")
		)
		(fp_line
			(start -0.15 0.4)
			(end 0.15 0.4)
			(stroke
				(width 0.15)
				(type solid)
			)
			(layer "F.SilkS")
		)
		(fp_rect
			(start -1.25 -0.65)
			(end 1.25 0.65)
			(stroke
				(width 0.05)
				(type solid)
			)
			(fill no)
			(layer "F.CrtYd")
		)
		(fp_rect
			(start -0.8 -0.4)
			(end 0.8 0.4)
			(stroke
				(width 0.15)
				(type solid)
			)
			(fill no)
			(layer "F.Fab")
		)
		(pad "1" smd roundrect
			(at -0.7 0)
			(size 0.8 1)
			(layers "F.Cu" "F.Mask" "F.Paste")
			(roundrect_rratio 0.2)
			(net 28 "GND")
			(pintype "passive")
		)
		(pad "2" smd roundrect
			(at 0.7 0)
			(size 0.8 1)
			(layers "F.Cu" "F.Mask" "F.Paste")
			(roundrect_rratio 0.2)
			(net 1 "VCCA")
			(pintype "passive")
		)
	)
	(footprint "antmicro-footprints:C_0402_1005Metric"
		(layer "F.Cu")
		(at 103.7 112.5 180)
		(descr "Capacitor SMD 0402")
		(tags "capacitor SMD 0402")
		(property "Reference" "C71"
			(at 0.85 0.35 0)
			(layer "F.SilkS")
			(effects
				(font
					(size 0.7 0.7)
					(thickness 0.15)
				)
				(justify right top)
			)
		)
		(property "Value" "C_100n_0402"
			(at -1.022927 2.155213 0)
			(layer "F.Fab")
			(hide yes)
			(effects
				(font
					(size 0.7 0.7)
					(thickness 0.15)
				)
				(justify right top)
			)
		)
		(property "Datasheet" "https://www.murata.com/products/productdetail?partno=GRM155R61H104KE14%23"
			(at 0 0 0)
			(layer "F.Fab")
			(hide yes)
			(effects
				(font
					(size 1.27 1.27)
					(thickness 0.15)
				)
			)
		)
		(property "Description" "SMD Multilayer Ceramic Capacitor, 0.1 µF, 50 V, 0402 [1005 Metric], ± 10%, X5R, GRM Series"
			(at 0 0 0)
			(layer "F.Fab")
			(hide yes)
			(effects
				(font
					(size 1.27 1.27)
					(thickness 0.15)
				)
			)
		)
		(property "MPN" "GRM155R61H104KE14D"
			(at 0 0 180)
			(unlocked yes)
			(layer "F.Fab")
			(hide yes)
			(effects
				(font
					(size 1 1)
					(thickness 0.15)
				)
			)
		)
		(property "Val" "100n"
			(at 0 0 180)
			(unlocked yes)
			(layer "F.Fab")
			(hide yes)
			(effects
				(font
					(size 1 1)
					(thickness 0.15)
				)
			)
		)
		(property "Voltage" "50V"
			(at 0 0 180)
			(unlocked yes)
			(layer "F.Fab")
			(hide yes)
			(effects
				(font
					(size 1 1)
					(thickness 0.15)
				)
			)
		)
		(property "Dielectric" "X5R"
			(at 0 0 180)
			(unlocked yes)
			(layer "F.Fab")
			(hide yes)
			(effects
				(font
					(size 1 1)
					(thickness 0.15)
				)
			)
		)
		(property "Manufacturer" "Murata"
			(at 0 0 180)
			(unlocked yes)
			(layer "F.Fab")
			(hide yes)
			(effects
				(font
					(size 1 1)
					(thickness 0.15)
				)
			)
		)
		(property "License" "Apache-2.0"
			(at 0 0 180)
			(unlocked yes)
			(layer "F.Fab")
			(hide yes)
			(effects
				(font
					(size 1 1)
					(thickness 0.15)
				)
			)
		)
		(property "Author" "Antmicro"
			(at 0 0 180)
			(unlocked yes)
			(layer "F.Fab")
			(hide yes)
			(effects
				(font
					(size 1 1)
					(thickness 0.15)
				)
			)
		)
		(sheetname "/X710-AT2 10GbE/")
		(sheetfile "x710-at2-10gbe.kicad_sch")
		(attr smd)
		(fp_rect
			(start -0.925 -0.47)
			(end 0.925 0.47)
			(stroke
				(width 0.05)
				(type default)
			)
			(fill no)
			(layer "F.CrtYd")
		)
		(fp_line
			(start 0.504 0.248)
			(end -0.494 0.248)
			(stroke
				(width 0.15)
				(type solid)
			)
			(layer "F.Fab")
		)
		(fp_line
			(start 0.504 -0.25)
			(end 0.504 0.248)
			(stroke
				(width 0.15)
				(type solid)
			)
			(layer "F.Fab")
		)
		(fp_line
			(start -0.494 0.248)
			(end -0.494 -0.25)
			(stroke
				(width 0.15)
				(type solid)
			)
			(layer "F.Fab")
		)
		(fp_line
			(start -0.494 -0.25)
			(end 0.504 -0.25)
			(stroke
				(width 0.15)
				(type solid)
			)
			(layer "F.Fab")
		)
		(pad "1" smd roundrect
			(at -0.48 0 180)
			(size 0.59 0.64)
			(layers "F.Cu" "F.Mask" "F.Paste")
			(roundrect_rratio 0.25)
			(net 28 "GND")
			(pintype "passive")
		)
		(pad "2" smd roundrect
			(at 0.48 0 180)
			(size 0.59 0.64)
			(layers "F.Cu" "F.Mask" "F.Paste")
			(roundrect_rratio 0.25)
			(net 74 "/X710-AT2 10GbE/3V3_OSC")
			(pintype "passive")
		)
	)
	(footprint "antmicro-footprints:LED_0603_1608Metric_G"
		(layer "F.Cu")
		(at 54.350001 120.4 180)
		(descr "LED SMD 0603 Green")
		(tags "LED SMD 0603 Green")
		(property "Reference" "D19"
			(at -1.099999 -0.75 0)
			(layer "F.SilkS")
			(effects
				(font
					(size 0.7 0.7)
					(thickness 0.15)
				)
				(justify right top)
			)
		)
		(property "Value" "LED_G_0603_LG_L29K-G2J1-24-Z"
			(at -0.001 1.599 0)
			(layer "F.Fab")
			(hide yes)
			(effects
				(font
					(size 0.7 0.7)
					(thickness 0.15)
				)
				(justify right top)
			)
		)
		(property "Datasheet" "https://look.ams-osram.com/m/19ee86b3ae0ee95b/original/LG-L29K.pdf"
			(at 0 0 0)
			(layer "F.Fab")
			(hide yes)
			(effects
				(font
					(size 1.27 1.27)
					(thickness 0.15)
				)
			)
		)
		(property "Description" "LED, Green, SMD, 0603, 20 mA, 1.7 V, 570 nm"
			(at 0 0 0)
			(layer "F.Fab")
			(hide yes)
			(effects
				(font
					(size 1.27 1.27)
					(thickness 0.15)
				)
			)
		)
		(property "MPN" "LG L29K-G2J1-24-Z"
			(at 0 0 180)
			(unlocked yes)
			(layer "F.Fab")
			(hide yes)
			(effects
				(font
					(size 1 1)
					(thickness 0.15)
				)
			)
		)
		(property "Manufacturer" "OSRAM"
			(at 0 0 180)
			(unlocked yes)
			(layer "F.Fab")
			(hide yes)
			(effects
				(font
					(size 1 1)
					(thickness 0.15)
				)
			)
		)
		(property "Color" "Green"
			(at 0 0 180)
			(unlocked yes)
			(layer "F.Fab")
			(hide yes)
			(effects
				(font
					(size 1 1)
					(thickness 0.15)
				)
			)
		)
		(property "Author" "Antmicro"
			(at 0 0 180)
			(unlocked yes)
			(layer "F.Fab")
			(hide yes)
			(effects
				(font
					(size 1 1)
					(thickness 0.15)
				)
			)
		)
		(property "License" "Apache-2.0"
			(at 0 0 180)
			(unlocked yes)
			(layer "F.Fab")
			(hide yes)
			(effects
				(font
					(size 1 1)
					(thickness 0.15)
				)
			)
		)
		(sheetname "/Power/")
		(sheetfile "power.kicad_sch")
		(attr smd)
		(fp_line
			(start 0.22 0.35)
			(end -0.22 0.35)
			(stroke
				(width 0.15)
				(type solid)
			)
			(layer "F.SilkS")
		)
		(fp_line
			(start 0.22 -0.35)
			(end -0.22 -0.35)
			(stroke
				(width 0.15)
				(type solid)
			)
			(layer "F.SilkS")
		)
		(fp_line
			(start 0.105328 0.201008)
			(end 0.105328 -0.198992)
			(stroke
				(width 0.1)
				(type solid)
			)
			(layer "F.SilkS")
		)
		(fp_line
			(start 0.105328 0.201008)
			(end -0.094672 0.001008)
			(stroke
				(width 0.1)
				(type solid)
			)
			(layer "F.SilkS")
		)
		(fp_line
			(start 0.105328 0.001008)
			(end 0.24 0.001)
			(stroke
				(width 0.1)
				(type solid)
			)
			(layer "F.SilkS")
		)
		(fp_line
			(start -0.094672 0.201008)
			(end -0.094672 -0.198992)
			(stroke
				(width 0.1)
				(type solid)
			)
			(layer "F.SilkS")
		)
		(fp_line
			(start -0.094672 0.001008)
			(end 0.105328 -0.198992)
			(stroke
				(width 0.1)
				(type solid)
			)
			(layer "F.SilkS")
		)
		(fp_line
			(start -0.094672 0.001008)
			(end -0.24 0.001008)
			(stroke
				(width 0.1)
				(type solid)
			)
			(layer "F.SilkS")
		)
		(fp_line
			(start -1.18 -0.319)
			(end -1.18 0.321)
			(stroke
				(width 0.15)
				(type solid)
			)
			(layer "F.SilkS")
		)
		(fp_rect
			(start 1.25 0.65)
			(end -1.25 -0.65)
			(stroke
				(width 0.05)
				(type solid)
			)
			(fill no)
			(layer "F.CrtYd")
		)
		(fp_line
			(start 0.599 0)
			(end 0.201 0)
			(stroke
				(width 0.15)
				(type solid)
			)
			(layer "F.Fab")
		)
		(fp_line
			(start 0.201 0.2)
			(end 0.201 0)
			(stroke
				(width 0.15)
				(type solid)
			)
			(layer "F.Fab")
		)
		(fp_line
			(start 0.201 0)
			(end 0.201 -0.202)
			(stroke
				(width 0.15)
				(type solid)
			)
			(layer "F.Fab")
		)
		(fp_line
			(start 0.201 -0.202)
			(end -0.101 0)
			(stroke
				(width 0.15)
				(type solid)
			)
			(layer "F.Fab")
		)
		(fp_line
			(start -0.101 0)
			(end 0.201 0.2)
			(stroke
				(width 0.15)
				(type solid)
			)
			(layer "F.Fab")
		)
		(fp_line
			(start -0.199 0.2)
			(end -0.199 0.1)
			(stroke
				(width 0.15)
				(type solid)
			)
			(layer "F.Fab")
		)
		(fp_line
			(start -0.199 0)
			(end -0.597 0)
			(stroke
				(width 0.15)
				(type solid)
			)
			(layer "F.Fab")
		)
		(fp_line
			(start -0.199 -0.202)
			(end -0.199 0.1)
			(stroke
				(width 0.15)
				(type solid)
			)
			(layer "F.Fab")
		)
		(fp_rect
			(start 0.848 0.4)
			(end -0.85 -0.402)
			(stroke
				(width 0.15)
				(type solid)
			)
			(fill no)
			(layer "F.Fab")
		)
		(fp_text user "License: Apache-2.0"
			(at -1.4224 3.599 180)
			(layer "F.Fab")
			(effects
				(font
					(size 0.7 0.7)
					(thickness 0.15)
				)
				(justify left bottom)
			)
		)
		(fp_text user "Author: Antmicro"
			(at -1.4224 4.799 180)
			(layer "F.Fab")
			(effects
				(font
					(size 0.7 0.7)
					(thickness 0.15)
				)
				(justify left bottom)
			)
		)
		(fp_text user "${REFERENCE}"
			(at -1.4224 5.999 180)
			(layer "F.Fab")
			(effects
				(font
					(size 0.7 0.7)
					(thickness 0.15)
				)
				(justify left bottom)
			)
		)
		(pad "1" smd roundrect
			(at -0.7 0)
			(size 0.8 1)
			(layers "F.Cu" "F.Mask" "F.Paste")
			(roundrect_rratio 0.2)
			(net 413 "Net-(D19-C)")
			(pinfunction "C")
			(pintype "passive")
		)
		(pad "2" smd roundrect
			(at 0.7 0)
			(size 0.8 1)
			(layers "F.Cu" "F.Mask" "F.Paste")
			(roundrect_rratio 0.2)
			(net 255 "/Power/+3V3_OUT")
			(pinfunction "A")
			(pintype "passive")
		)
	)
	(footprint "antmicro-footprints:R_0603_1608Metric"
		(layer "F.Cu")
		(at 63.2 99.500001)
		(descr "Resistor SMD 0603")
		(tags "resistor SMD 0603")
		(property "Reference" "R14"
			(at -0.04 -0.660001 0)
			(layer "F.SilkS")
			(effects
				(font
					(size 0.7 0.7)
					(thickness 0.15)
				)
				(justify left bottom)
			)
		)
		(property "Value" "R_0R_22.4A_0603"
			(at 0 1.6 0)
			(layer "F.Fab")
			(hide yes)
			(effects
				(font
					(size 0.7 0.7)
					(thickness 0.15)
				)
				(justify left bottom)
			)
		)
		(property "Datasheet" "https://fscdn.rohm.com/en/products/databook/datasheet/passive/resistor/chip_resistor/pmr-jpw-e.pdf"
			(at 0 0 0)
			(layer "F.Fab")
			(hide yes)
			(effects
				(font
					(size 1.27 1.27)
					(thickness 0.15)
				)
			)
		)
		(property "Description" "SMD Chip Resistor"
			(at 0 0 0)
			(layer "F.Fab")
			(hide yes)
			(effects
				(font
					(size 1.27 1.27)
					(thickness 0.15)
				)
			)
		)
		(property "MPN" "PMR03EZPJ000"
			(at 0 0 0)
			(unlocked yes)
			(layer "F.Fab")
			(hide yes)
			(effects
				(font
					(size 1 1)
					(thickness 0.15)
				)
			)
		)
		(property "Manufacturer" "ROHM Semiconductor"
			(at 0 0 0)
			(unlocked yes)
			(layer "F.Fab")
			(hide yes)
			(effects
				(font
					(size 1 1)
					(thickness 0.15)
				)
			)
		)
		(property "Val" "0R"
			(at 0 0 0)
			(unlocked yes)
			(layer "F.Fab")
			(hide yes)
			(effects
				(font
					(size 1 1)
					(thickness 0.15)
				)
			)
		)
		(property "Max. Curr." "22.4A"
			(at 0 0 0)
			(unlocked yes)
			(layer "F.Fab")
			(hide yes)
			(effects
				(font
					(size 1 1)
					(thickness 0.15)
				)
			)
		)
		(property "Author" "Antmicro"
			(at 0 0 0)
			(unlocked yes)
			(layer "F.Fab")
			(hide yes)
			(effects
				(font
					(size 1 1)
					(thickness 0.15)
				)
			)
		)
		(property "License" "Apache-2.0"
			(at 0 0 0)
			(unlocked yes)
			(layer "F.Fab")
			(hide yes)
			(effects
				(font
					(size 1 1)
					(thickness 0.15)
				)
			)
		)
		(property "Tolerance" "template_tolerance"
			(at 0 0 0)
			(unlocked yes)
			(layer "F.Fab")
			(hide yes)
			(effects
				(font
					(size 1 1)
					(thickness 0.15)
				)
			)
		)
		(sheetname "/Power/")
		(sheetfile "power.kicad_sch")
		(attr smd)
		(fp_line
			(start -0.15 -0.4)
			(end 0.15 -0.4)
			(stroke
				(width 0.15)
				(type solid)
			)
			(layer "F.SilkS")
		)
		(fp_line
			(start -0.15 0.4)
			(end 0.15 0.4)
			(stroke
				(width 0.15)
				(type solid)
			)
			(layer "F.SilkS")
		)
		(fp_rect
			(start -1.25 -0.65)
			(end 1.25 0.65)
			(stroke
				(width 0.05)
				(type solid)
			)
			(fill no)
			(layer "F.CrtYd")
		)
		(fp_rect
			(start -0.8 -0.4)
			(end 0.8 0.4)
			(stroke
				(width 0.15)
				(type solid)
			)
			(fill no)
			(layer "F.Fab")
		)
		(pad "1" smd roundrect
			(at -0.7 0)
			(size 0.8 1)
			(layers "F.Cu" "F.Mask" "F.Paste")
			(roundrect_rratio 0.2)
			(net 310 "/Power/+1V88_OUT")
			(pintype "passive")
		)
		(pad "2" smd roundrect
			(at 0.7 0)
			(size 0.8 1)
			(layers "F.Cu" "F.Mask" "F.Paste")
			(roundrect_rratio 0.2)
			(net 18 "+1V88")
			(pintype "passive")
		)
	)
)
